(kicad_pcb
	(version 20260206)
	(generator "pcbnew")
	(generator_version "10.0")
	(general
		(thickness 1.6)
		(legacy_teardrops no)
	)
	(paper "A4")
	(title_block
		(title "baseboard — 13948-1b.1110WZS1818.brd")
		(comment 1 "Honey Badger (Wiwynn) / footprints 2135-2141 of 2523")
	)
	(layers
		(0 "F.Cu" signal "TOP")
		(4 "In1.Cu" signal "L2GND")
		(6 "In2.Cu" signal "L3")
		(8 "In3.Cu" signal "L4VCC")
		(10 "In4.Cu" signal "L5VCC")
		(12 "In5.Cu" signal "L6")
		(14 "In6.Cu" signal "L7GND")
		(2 "B.Cu" signal "BOTTOM")
		(9 "F.Adhes" user "F.Adhesive")
		(11 "B.Adhes" user "B.Adhesive")
		(13 "F.Paste" user "Package Geometry/Pastemask Top")
		(15 "B.Paste" user "Package Geometry/Pastemask Bottom")
		(5 "F.SilkS" user "Ref Des/Silkscreen Top")
		(7 "B.SilkS" user "Ref Des/Silkscreen Bottom")
		(1 "F.Mask" user "Board Geometry/Soldermask Top")
		(3 "B.Mask" user "Board Geometry/Soldermask Bottom")
		(17 "Dwgs.User" user "User.Drawings")
		(19 "Cmts.User" user "User.Comments")
		(21 "Eco1.User" user "User.Eco1")
		(23 "Eco2.User" user "User.Eco2")
		(25 "Edge.Cuts" user "Board Geometry/Outline")
		(27 "Margin" user)
		(31 "F.CrtYd" user "Package Geometry/Place Bound Top")
		(29 "B.CrtYd" user "Package Geometry/Place Bound Bottom")
		(35 "F.Fab" user "Ref Des/Assembly Top")
		(33 "B.Fab" user "Ref Des/Assembly Bottom")
	)
	(footprint ""
		(layer "B.Cu")
		(at 347.472 -115.951)
		(property "Reference" "PG2"
			(at 0 0 0)
			(layer "B.SilkS")
			(hide yes)
			(effects
				(font
					(size 1.27 1.27)
				)
				(justify mirror)
			)
		)
		(property "Value" "COPPER-CLOSE-GP-U"
			(at -0.0762 -2.8702 0)
			(unlocked yes)
			(layer "B.Fab")
			(hide yes)
			(effects
				(font
					(size 1.016 1.016)
					(thickness 0.1524)
				)
				(justify mirror)
			)
		)
		(property "Device Type" "CON2C-U"
			(at -0.0762 -4.3942 0)
			(unlocked yes)
			(layer "B.Fab")
			(hide yes)
			(effects
				(font
					(size 1.016 1.016)
					(thickness 0.1524)
				)
				(justify mirror)
			)
		)
		(duplicate_pad_numbers_are_jumpers no)
		(fp_rect
			(start 0.9398 0.9652)
			(end -0.9398 -0.9652)
			(stroke
				(width 0)
				(type default)
			)
			(fill no)
			(layer "B.CrtYd")
		)
		(fp_rect
			(start 0.9398 0.9652)
			(end -0.9398 -0.9652)
			(stroke
				(width 0)
				(type default)
			)
			(fill no)
			(layer "B.Fab")
		)
		(pad "1" smd custom
			(at 0 -0.5334 180)
			(size 0.17145 0.17145)
			(layers "B.Cu" "B.Mask" "B.Paste")
			(net "AGND_P5V_STBY")
			(options
				(clearance outline)
				(anchor circle)
			)
			(primitives
				(gr_poly
					(pts
						(xy -0.127 -0.3429) (xy -0.127 -0.1651) (xy -0.635 0.3429) (xy 0.635 0.3429) (xy 0.127 -0.1651)
						(xy 0.127 -0.3429)
					)
					(width 0)
					(fill yes)
				)
			)
		)
		(pad "2" smd custom
			(at 0 0.5334 180)
			(size 0.17145 0.17145)
			(layers "B.Cu" "B.Mask" "B.Paste")
			(net "GND")
			(options
				(clearance outline)
				(anchor circle)
			)
			(primitives
				(gr_poly
					(pts
						(xy -0.635 -0.3429) (xy -0.127 0.1651) (xy -0.127 0.3429) (xy 0.127 0.3429) (xy 0.127 0.1651)
						(xy 0.635 -0.3429)
					)
					(width 0)
					(fill yes)
				)
			)
		)
	)
	(footprint ""
		(layer "B.Cu")
		(at 101.454966 -48.26 -90)
		(property "Reference" "SC1054"
			(at 0 0 90)
			(layer "B.SilkS")
			(hide yes)
			(effects
				(font
					(size 1.27 1.27)
				)
				(justify mirror)
			)
		)
		(property "Value" "SCD1U16V2KX-3GP"
			(at -1.1811 -2.7051 270)
			(unlocked yes)
			(layer "B.Fab")
			(hide yes)
			(effects
				(font
					(size 1.016 1.016)
					(thickness 0.1524)
				)
				(justify mirror)
			)
		)
		(property "Device Type" "C402H22"
			(at -1.1811 -4.2291 270)
			(unlocked yes)
			(layer "B.Fab")
			(hide yes)
			(effects
				(font
					(size 1.016 1.016)
					(thickness 0.1524)
				)
				(justify mirror)
			)
		)
		(duplicate_pad_numbers_are_jumpers no)
		(fp_rect
			(start 0.4318 0.9525)
			(end -0.4318 -0.9525)
			(stroke
				(width 0)
				(type default)
			)
			(fill no)
			(layer "B.CrtYd")
		)
		(fp_rect
			(start 0.4318 0.9525)
			(end -0.4318 -0.9525)
			(stroke
				(width 0)
				(type default)
			)
			(fill no)
			(layer "B.Fab")
		)
		(pad "1" smd custom
			(at 0 -0.4445 90)
			(size 0.1524 0.1524)
			(layers "B.Cu" "B.Mask" "B.Paste")
			(net "P0V955_C")
			(options
				(clearance outline)
				(anchor circle)
			)
			(primitives
				(gr_poly
					(pts
						(arc
							(start 0.3048 0.2032)
							(mid 0.275042 0.275042)
							(end 0.2032 0.3048)
						)
						(arc
							(start -0.2032 0.3048)
							(mid -0.275042 0.275042)
							(end -0.3048 0.2032)
						)
						(arc
							(start -0.3048 -0.2032)
							(mid -0.275042 -0.275042)
							(end -0.2032 -0.3048)
						)
						(arc
							(start 0.2032 -0.3048)
							(mid 0.275042 -0.275042)
							(end 0.3048 -0.2032)
						)
					)
					(width 0)
					(fill yes)
				)
			)
		)
		(pad "2" smd custom
			(at 0 0.4445 90)
			(size 0.1524 0.1524)
			(layers "B.Cu" "B.Mask" "B.Paste")
			(net "GND")
			(options
				(clearance outline)
				(anchor circle)
			)
			(primitives
				(gr_poly
					(pts
						(arc
							(start 0.3048 0.2032)
							(mid 0.275042 0.275042)
							(end 0.2032 0.3048)
						)
						(arc
							(start -0.2032 0.3048)
							(mid -0.275042 0.275042)
							(end -0.3048 0.2032)
						)
						(arc
							(start -0.3048 -0.2032)
							(mid -0.275042 -0.275042)
							(end -0.2032 -0.3048)
						)
						(arc
							(start 0.2032 -0.3048)
							(mid 0.275042 -0.275042)
							(end 0.3048 -0.2032)
						)
					)
					(width 0)
					(fill yes)
				)
			)
		)
	)
	(footprint ""
		(layer "B.Cu")
		(at 103.385366 -41.91 90)
		(property "Reference" "SC1058"
			(at 0 0 90)
			(layer "B.SilkS")
			(hide yes)
			(effects
				(font
					(size 1.27 1.27)
				)
				(justify mirror)
			)
		)
		(property "Value" "SCD1U16V2KX-3GP"
			(at -1.1811 -2.7051 90)
			(unlocked yes)
			(layer "B.Fab")
			(hide yes)
			(effects
				(font
					(size 1.016 1.016)
					(thickness 0.1524)
				)
				(justify mirror)
			)
		)
		(property "Device Type" "C402H22"
			(at -1.1811 -4.2291 90)
			(unlocked yes)
			(layer "B.Fab")
			(hide yes)
			(effects
				(font
					(size 1.016 1.016)
					(thickness 0.1524)
				)
				(justify mirror)
			)
		)
		(duplicate_pad_numbers_are_jumpers no)
		(fp_rect
			(start 0.4318 0.9525)
			(end -0.4318 -0.9525)
			(stroke
				(width 0)
				(type default)
			)
			(fill no)
			(layer "B.CrtYd")
		)
		(fp_rect
			(start 0.4318 0.9525)
			(end -0.4318 -0.9525)
			(stroke
				(width 0)
				(type default)
			)
			(fill no)
			(layer "B.Fab")
		)
		(pad "1" smd custom
			(at 0 -0.4445 270)
			(size 0.1524 0.1524)
			(layers "B.Cu" "B.Mask" "B.Paste")
			(net "P0V955_C")
			(options
				(clearance outline)
				(anchor circle)
			)
			(primitives
				(gr_poly
					(pts
						(arc
							(start 0.3048 0.2032)
							(mid 0.275042 0.275042)
							(end 0.2032 0.3048)
						)
						(arc
							(start -0.2032 0.3048)
							(mid -0.275042 0.275042)
							(end -0.3048 0.2032)
						)
						(arc
							(start -0.3048 -0.2032)
							(mid -0.275042 -0.275042)
							(end -0.2032 -0.3048)
						)
						(arc
							(start 0.2032 -0.3048)
							(mid 0.275042 -0.275042)
							(end 0.3048 -0.2032)
						)
					)
					(width 0)
					(fill yes)
				)
			)
		)
		(pad "2" smd custom
			(at 0 0.4445 270)
			(size 0.1524 0.1524)
			(layers "B.Cu" "B.Mask" "B.Paste")
			(net "GND")
			(options
				(clearance outline)
				(anchor circle)
			)
			(primitives
				(gr_poly
					(pts
						(arc
							(start 0.3048 0.2032)
							(mid 0.275042 0.275042)
							(end 0.2032 0.3048)
						)
						(arc
							(start -0.2032 0.3048)
							(mid -0.275042 0.275042)
							(end -0.3048 0.2032)
						)
						(arc
							(start -0.3048 -0.2032)
							(mid -0.275042 -0.275042)
							(end -0.2032 -0.3048)
						)
						(arc
							(start 0.2032 -0.3048)
							(mid 0.275042 -0.275042)
							(end 0.3048 -0.2032)
						)
					)
					(width 0)
					(fill yes)
				)
			)
		)
	)
	(footprint ""
		(layer "B.Cu")
		(at 92.686886 -48.747426 180)
		(property "Reference" "SC1066"
			(at 0 0 0)
			(layer "B.SilkS")
			(hide yes)
			(effects
				(font
					(size 1.27 1.27)
				)
				(justify mirror)
			)
		)
		(property "Value" "SCD1U16V2KX-3GP"
			(at -1.1811 -2.7051 180)
			(unlocked yes)
			(layer "B.Fab")
			(hide yes)
			(effects
				(font
					(size 1.016 1.016)
					(thickness 0.1524)
				)
				(justify mirror)
			)
		)
		(property "Device Type" "C402H22"
			(at -1.1811 -4.2291 180)
			(unlocked yes)
			(layer "B.Fab")
			(hide yes)
			(effects
				(font
					(size 1.016 1.016)
					(thickness 0.1524)
				)
				(justify mirror)
			)
		)
		(duplicate_pad_numbers_are_jumpers no)
		(fp_rect
			(start 0.4318 0.9525)
			(end -0.4318 -0.9525)
			(stroke
				(width 0)
				(type default)
			)
			(fill no)
			(layer "B.CrtYd")
		)
		(fp_rect
			(start 0.4318 0.9525)
			(end -0.4318 -0.9525)
			(stroke
				(width 0)
				(type default)
			)
			(fill no)
			(layer "B.Fab")
		)
		(pad "1" smd custom
			(at 0 -0.4445)
			(size 0.1524 0.1524)
			(layers "B.Cu" "B.Mask" "B.Paste")
			(net "P1V8_C")
			(options
				(clearance outline)
				(anchor circle)
			)
			(primitives
				(gr_poly
					(pts
						(arc
							(start 0.3048 0.2032)
							(mid 0.275042 0.275042)
							(end 0.2032 0.3048)
						)
						(arc
							(start -0.2032 0.3048)
							(mid -0.275042 0.275042)
							(end -0.3048 0.2032)
						)
						(arc
							(start -0.3048 -0.2032)
							(mid -0.275042 -0.275042)
							(end -0.2032 -0.3048)
						)
						(arc
							(start 0.2032 -0.3048)
							(mid 0.275042 -0.275042)
							(end 0.3048 -0.2032)
						)
					)
					(width 0)
					(fill yes)
				)
			)
		)
		(pad "2" smd custom
			(at 0 0.4445)
			(size 0.1524 0.1524)
			(layers "B.Cu" "B.Mask" "B.Paste")
			(net "GND")
			(options
				(clearance outline)
				(anchor circle)
			)
			(primitives
				(gr_poly
					(pts
						(arc
							(start 0.3048 0.2032)
							(mid 0.275042 0.275042)
							(end 0.2032 0.3048)
						)
						(arc
							(start -0.2032 0.3048)
							(mid -0.275042 0.275042)
							(end -0.3048 0.2032)
						)
						(arc
							(start -0.3048 -0.2032)
							(mid -0.275042 -0.275042)
							(end -0.2032 -0.3048)
						)
						(arc
							(start 0.2032 -0.3048)
							(mid 0.275042 -0.275042)
							(end 0.3048 -0.2032)
						)
					)
					(width 0)
					(fill yes)
				)
			)
		)
	)
	(footprint ""
		(layer "B.Cu")
		(at 341.507318 -133.353048 -90)
		(property "Reference" "R554"
			(at 0 0 90)
			(layer "B.SilkS")
			(hide yes)
			(effects
				(font
					(size 1.27 1.27)
				)
				(justify mirror)
			)
		)
		(property "Value" "0R3J-0-U-GP"
			(at 0.0254 -2.5146 270)
			(unlocked yes)
			(layer "B.Fab")
			(hide yes)
			(effects
				(font
					(size 1.016 1.016)
					(thickness 0.1524)
				)
				(justify mirror)
			)
		)
		(property "Device Type" "R603H22"
			(at 0.0254 -4.0386 270)
			(unlocked yes)
			(layer "B.Fab")
			(hide yes)
			(effects
				(font
					(size 1.016 1.016)
					(thickness 0.1524)
				)
				(justify mirror)
			)
		)
		(duplicate_pad_numbers_are_jumpers no)
		(fp_line
			(start -0.2032 0)
			(end -0.4826 0)
			(stroke
				(width 0.2032)
				(type default)
			)
			(layer "B.SilkS")
		)
		(fp_line
			(start 0.4826 0)
			(end 0.2032 0)
			(stroke
				(width 0.2032)
				(type default)
			)
			(layer "B.SilkS")
		)
		(fp_rect
			(start 0.5842 1.3335)
			(end -0.5842 -1.3335)
			(stroke
				(width 0)
				(type default)
			)
			(fill no)
			(layer "B.CrtYd")
		)
		(fp_rect
			(start 0.5842 1.3335)
			(end -0.5842 -1.3335)
			(stroke
				(width 0)
				(type default)
			)
			(fill no)
			(layer "B.Fab")
		)
		(pad "1" smd custom
			(at 0 -0.762 90)
			(size 0.2159 0.2159)
			(layers "B.Cu" "B.Mask" "B.Paste")
			(net "USB_P1_DP")
			(options
				(clearance outline)
				(anchor circle)
			)
			(primitives
				(gr_poly
					(pts
						(arc
							(start -0.3302 0.4318)
							(mid -0.402042 0.402042)
							(end -0.4318 0.3302)
						)
						(arc
							(start -0.4318 -0.3302)
							(mid -0.402042 -0.402042)
							(end -0.3302 -0.4318)
						)
						(arc
							(start 0.3302 -0.4318)
							(mid 0.402042 -0.402042)
							(end 0.4318 -0.3302)
						)
						(arc
							(start 0.4318 0.3302)
							(mid 0.402042 0.402042)
							(end 0.3302 0.4318)
						)
					)
					(width 0)
					(fill yes)
				)
			)
		)
		(pad "2" smd custom
			(at 0 0.762 90)
			(size 0.2159 0.2159)
			(layers "B.Cu" "B.Mask" "B.Paste")
			(net "USB_DP_R")
			(options
				(clearance outline)
				(anchor circle)
			)
			(primitives
				(gr_poly
					(pts
						(arc
							(start -0.3302 0.4318)
							(mid -0.402042 0.402042)
							(end -0.4318 0.3302)
						)
						(arc
							(start -0.4318 -0.3302)
							(mid -0.402042 -0.402042)
							(end -0.3302 -0.4318)
						)
						(arc
							(start 0.3302 -0.4318)
							(mid 0.402042 -0.402042)
							(end 0.4318 -0.3302)
						)
						(arc
							(start 0.4318 0.3302)
							(mid 0.402042 0.402042)
							(end 0.3302 0.4318)
						)
					)
					(width 0)
					(fill yes)
				)
			)
		)
	)
	(footprint ""
		(layer "B.Cu")
		(at 271.238472 -173.114716 90)
		(property "Reference" "R257"
			(at 0 0 90)
			(layer "B.SilkS")
			(hide yes)
			(effects
				(font
					(size 1.27 1.27)
				)
				(justify mirror)
			)
		)
		(property "Value" "10KR2F-2-GP"
			(at -0.064008 -3.993896 90)
			(unlocked yes)
			(layer "B.Fab")
			(hide yes)
			(effects
				(font
					(size 1.016 1.016)
					(thickness 0.1524)
				)
				(justify mirror)
			)
		)
		(property "Device Type" "R402H16"
			(at -0.064008 -5.517896 90)
			(unlocked yes)
			(layer "B.Fab")
			(hide yes)
			(effects
				(font
					(size 1.016 1.016)
					(thickness 0.1524)
				)
				(justify mirror)
			)
		)
		(duplicate_pad_numbers_are_jumpers no)
		(fp_line
			(start 0.508 -0.9398)
			(end 0.508 0.9398)
			(stroke
				(width 0.1524)
				(type default)
			)
			(layer "B.SilkS")
		)
		(fp_line
			(start -0.508 -0.9398)
			(end 0.508 -0.9398)
			(stroke
				(width 0.1524)
				(type default)
			)
			(layer "B.SilkS")
		)
		(fp_rect
			(start 0.508 0.9398)
			(end -0.508 -0.9398)
			(stroke
				(width 0)
				(type default)
			)
			(fill no)
			(layer "B.CrtYd")
		)
		(fp_rect
			(start 0.508 0.9398)
			(end -0.508 -0.9398)
			(stroke
				(width 0)
				(type default)
			)
			(fill no)
			(layer "B.Fab")
		)
		(pad "1" smd custom
			(at 0 -0.4445 270)
			(size 0.1397 0.1397)
			(layers "B.Cu" "B.Mask" "B.Paste")
			(net "P3V3_STBY")
			(options
				(clearance outline)
				(anchor circle)
			)
			(primitives
				(gr_poly
					(pts
						(arc
							(start -0.1778 0.2794)
							(mid -0.249642 0.249642)
							(end -0.2794 0.1778)
						)
						(arc
							(start -0.2794 -0.1778)
							(mid -0.249642 -0.249642)
							(end -0.1778 -0.2794)
						)
						(arc
							(start 0.1778 -0.2794)
							(mid 0.249642 -0.249642)
							(end 0.2794 -0.1778)
						)
						(arc
							(start 0.2794 0.1778)
							(mid 0.249642 0.249642)
							(end 0.1778 0.2794)
						)
					)
					(width 0)
					(fill yes)
				)
			)
		)
		(pad "2" smd custom
			(at 0 0.4445 270)
			(size 0.1397 0.1397)
			(layers "B.Cu" "B.Mask" "B.Paste")
			(net "SAS_SEB_PEER_PRSNT_BMC")
			(options
				(clearance outline)
				(anchor circle)
			)
			(primitives
				(gr_poly
					(pts
						(arc
							(start -0.1778 0.2794)
							(mid -0.249642 0.249642)
							(end -0.2794 0.1778)
						)
						(arc
							(start -0.2794 -0.1778)
							(mid -0.249642 -0.249642)
							(end -0.1778 -0.2794)
						)
						(arc
							(start 0.1778 -0.2794)
							(mid 0.249642 -0.249642)
							(end 0.2794 -0.1778)
						)
						(arc
							(start 0.2794 0.1778)
							(mid 0.249642 0.249642)
							(end 0.1778 0.2794)
						)
					)
					(width 0)
					(fill yes)
				)
			)
		)
	)
	(footprint ""
		(layer "B.Cu")
		(at 318.008 -178.689 -90)
		(property "Reference" "R318"
			(at 0 0 90)
			(layer "B.SilkS")
			(hide yes)
			(effects
				(font
					(size 1.27 1.27)
				)
				(justify mirror)
			)
		)
		(property "Value" "0R2J-2-GP"
			(at -0.064008 -3.993896 270)
			(unlocked yes)
			(layer "B.Fab")
			(hide yes)
			(effects
				(font
					(size 1.016 1.016)
					(thickness 0.1524)
				)
				(justify mirror)
			)
		)
		(property "Device Type" "R402H16"
			(at -0.064008 -5.517896 270)
			(unlocked yes)
			(layer "B.Fab")
			(hide yes)
			(effects
				(font
					(size 1.016 1.016)
					(thickness 0.1524)
				)
				(justify mirror)
			)
		)
		(duplicate_pad_numbers_are_jumpers no)
		(fp_line
			(start -0.508 -0.9398)
			(end 0.508 -0.9398)
			(stroke
				(width 0.1524)
				(type default)
			)
			(layer "B.SilkS")
		)
		(fp_line
			(start 0.508 -0.9398)
			(end 0.508 0.9398)
			(stroke
				(width 0.1524)
				(type default)
			)
			(layer "B.SilkS")
		)
		(fp_rect
			(start 0.508 0.9398)
			(end -0.508 -0.9398)
			(stroke
				(width 0)
				(type default)
			)
			(fill no)
			(layer "B.CrtYd")
		)
		(fp_rect
			(start 0.508 0.9398)
			(end -0.508 -0.9398)
			(stroke
				(width 0)
				(type default)
			)
			(fill no)
			(layer "B.Fab")
		)
		(pad "1" smd custom
			(at 0 -0.4445 90)
			(size 0.1397 0.1397)
			(layers "B.Cu" "B.Mask" "B.Paste")
			(net "ADC_P3V3_STBY")
			(options
				(clearance outline)
				(anchor circle)
			)
			(primitives
				(gr_poly
					(pts
						(arc
							(start -0.1778 0.2794)
							(mid -0.249642 0.249642)
							(end -0.2794 0.1778)
						)
						(arc
							(start -0.2794 -0.1778)
							(mid -0.249642 -0.249642)
							(end -0.1778 -0.2794)
						)
						(arc
							(start 0.1778 -0.2794)
							(mid 0.249642 -0.249642)
							(end 0.2794 -0.1778)
						)
						(arc
							(start 0.2794 0.1778)
							(mid 0.249642 0.249642)
							(end 0.1778 0.2794)
						)
					)
					(width 0)
					(fill yes)
				)
			)
		)
		(pad "2" smd custom
			(at 0 0.4445 90)
			(size 0.1397 0.1397)
			(layers "B.Cu" "B.Mask" "B.Paste")
			(net "ADC_P3V3_STBY_BMC")
			(options
				(clearance outline)
				(anchor circle)
			)
			(primitives
				(gr_poly
					(pts
						(arc
							(start -0.1778 0.2794)
							(mid -0.249642 0.249642)
							(end -0.2794 0.1778)
						)
						(arc
							(start -0.2794 -0.1778)
							(mid -0.249642 -0.249642)
							(end -0.1778 -0.2794)
						)
						(arc
							(start 0.1778 -0.2794)
							(mid 0.249642 -0.249642)
							(end 0.2794 -0.1778)
						)
						(arc
							(start 0.2794 0.1778)
							(mid 0.249642 0.249642)
							(end 0.1778 0.2794)
						)
					)
					(width 0)
					(fill yes)
				)
			)
		)
	)
)
